# T6G (Grand Teton) — schematic netlist excerpt (pin names and nets, part order shuffled) for the footprints in the layout excerpt that follows; sources: Cadence DE-HDL packaged netlist, KiCad conversion of 04192023_DAF0TMB3IC0_F0TG_MB_C_brd_V02_OCP.brd

C2047  Q_CAP  0.1UF 25V 10% X7R  pkg 0402  page 257 : A = P3V3_AUX_ADC_TIC ; B = GND
R4071  Q_RES  10K 1% CHIP  pkg 0402LF  page 152 : A = P12V_AUX ; B = P12V_SCM_EN_G
C53  Q_CAP_DIFFBUS  DIFF BUS_0.22UF 6.3V 20% X6S  pkg C0201  page 67 : \1\ = P5E_CPU1_P3_TX_C_DP<13> ; \2\ = P5E_CPU1_P3_TX_DP<13>

(kicad_pcb
	(version 20260206)
	(generator "pcbnew")
	(generator_version "10.0")
	(general
		(thickness 1.6)
		(legacy_teardrops no)
	)
	(paper "A4")
	(title_block
		(title "04192023_DAF0TMB3IC0_F0TG_MB_C_brd_V02_OCP.brd")
		(comment 1 "Grand Teton / footprints 4749-4751 of 8354")
	)
	(layers
		(0 "F.Cu" signal "TOP")
		(4 "In1.Cu" signal "GND")
		(6 "In2.Cu" signal "IN1")
		(8 "In3.Cu" signal "GND1")
		(10 "In4.Cu" signal "IN2")
		(12 "In5.Cu" signal "GND2")
		(14 "In6.Cu" signal "IN3")
		(16 "In7.Cu" signal "GND3")
		(18 "In8.Cu" signal "VCC")
		(20 "In9.Cu" signal "VCC1")
		(22 "In10.Cu" signal "GND4")
		(24 "In11.Cu" signal "IN4")
		(26 "In12.Cu" signal "GND5")
		(28 "In13.Cu" signal "IN5")
		(30 "In14.Cu" signal "GND6")
		(32 "In15.Cu" signal "IN6")
		(34 "In16.Cu" signal "GND7")
		(2 "B.Cu" signal "BOTTOM")
		(9 "F.Adhes" user "F.Adhesive")
		(11 "B.Adhes" user "B.Adhesive")
		(13 "F.Paste" user "Package Geometry/Pastemask Top")
		(15 "B.Paste" user "Package Geometry/Pastemask Bottom")
		(5 "F.SilkS" user "Ref Des/Silkscreen Top")
		(7 "B.SilkS" user "Ref Des/Silkscreen Bottom")
		(1 "F.Mask" user "Board Geometry/Soldermask Top")
		(3 "B.Mask" user "Board Geometry/Soldermask Bottom")
		(17 "Dwgs.User" user "User.Drawings")
		(19 "Cmts.User" user "User.Comments")
		(21 "Eco1.User" user "User.Eco1")
		(23 "Eco2.User" user "User.Eco2")
		(25 "Edge.Cuts" user "Board Geometry/Outline")
		(27 "Margin" user)
		(31 "F.CrtYd" user "Package Geometry/Place Bound Top")
		(29 "B.CrtYd" user "Package Geometry/Place Bound Bottom")
		(35 "F.Fab" user "Ref Des/Assembly Top")
		(33 "B.Fab" user "Ref Des/Assembly Bottom")
	)
	(footprint ""
		(layer "F.Cu")
		(at 135.616696 -370.57203 -90)
		(property "Reference" "C53"
			(at 0 0 270)
			(layer "F.SilkS")
			(hide yes)
			(effects
				(font
					(size 1.27 1.27)
				)
			)
		)
		(property "Value" ""
			(at 0 0 270)
			(layer "F.Fab")
			(effects
				(font
					(size 1.27 1.27)
				)
			)
		)
		(duplicate_pad_numbers_are_jumpers no)
		(fp_line
			(start -0.299974 0.150114)
			(end -0.299974 -0.150114)
			(stroke
				(width 0.1)
				(type default)
			)
			(layer "F.Fab")
		)
		(fp_line
			(start 0.299974 0.150114)
			(end -0.299974 0.150114)
			(stroke
				(width 0.1)
				(type default)
			)
			(layer "F.Fab")
		)
		(fp_line
			(start -0.299974 -0.150114)
			(end 0.299974 -0.150114)
			(stroke
				(width 0.1)
				(type default)
			)
			(layer "F.Fab")
		)
		(fp_line
			(start 0.299974 -0.150114)
			(end 0.299974 0.150114)
			(stroke
				(width 0.1)
				(type default)
			)
			(layer "F.Fab")
		)
		(pad "1" smd rect
			(at -0.2667 0 270)
			(size 0.3048 0.381)
			(layers "F.Cu" "F.Mask" "F.Paste")
			(net "P5E_CPU1_P3_TX_C_DP<13>")
		)
		(pad "2" smd rect
			(at 0.2667 0 270)
			(size 0.3048 0.381)
			(layers "F.Cu" "F.Mask" "F.Paste")
			(net "P5E_CPU1_P3_TX_DP<13>")
		)
	)
	(footprint ""
		(layer "F.Cu")
		(at 190.4238 -42.554398)
		(property "Reference" "R4071"
			(at 0 0 0)
			(layer "F.SilkS")
			(hide yes)
			(effects
				(font
					(size 1.27 1.27)
				)
			)
		)
		(property "Value" ""
			(at 0 0 0)
			(layer "F.Fab")
			(effects
				(font
					(size 1.27 1.27)
				)
			)
		)
		(duplicate_pad_numbers_are_jumpers no)
		(fp_line
			(start -0.7874 -0.4064)
			(end 0.7874 -0.4064)
			(stroke
				(width 0.1524)
				(type default)
			)
			(layer "F.SilkS")
		)
		(fp_line
			(start -0.7874 0.4064)
			(end -0.7874 -0.4064)
			(stroke
				(width 0.1524)
				(type default)
			)
			(layer "F.SilkS")
		)
		(fp_line
			(start 0.7874 -0.4064)
			(end 0.7874 0.4064)
			(stroke
				(width 0.1524)
				(type default)
			)
			(layer "F.SilkS")
		)
		(fp_line
			(start 0.7874 0.4064)
			(end -0.7874 0.4064)
			(stroke
				(width 0.1524)
				(type default)
			)
			(layer "F.SilkS")
		)
		(fp_line
			(start -0.67945 -0.305054)
			(end -0.12065 -0.305054)
			(stroke
				(width 0.1)
				(type default)
			)
			(layer "F.Fab")
		)
		(fp_line
			(start -0.67945 0.3048)
			(end -0.67945 -0.305054)
			(stroke
				(width 0.1)
				(type default)
			)
			(layer "F.Fab")
		)
		(fp_line
			(start -0.12065 -0.305054)
			(end -0.12065 -0.2794)
			(stroke
				(width 0.1)
				(type default)
			)
			(layer "F.Fab")
		)
		(fp_line
			(start -0.12065 -0.2794)
			(end 0.12065 -0.2794)
			(stroke
				(width 0.1)
				(type default)
			)
			(layer "F.Fab")
		)
		(fp_line
			(start -0.12065 0.2794)
			(end -0.12065 0.3048)
			(stroke
				(width 0.1)
				(type default)
			)
			(layer "F.Fab")
		)
		(fp_line
			(start -0.12065 0.3048)
			(end -0.67945 0.3048)
			(stroke
				(width 0.1)
				(type default)
			)
			(layer "F.Fab")
		)
		(fp_line
			(start 0.120396 0.2794)
			(end -0.12065 0.2794)
			(stroke
				(width 0.1)
				(type default)
			)
			(layer "F.Fab")
		)
		(fp_line
			(start 0.120396 0.3048)
			(end 0.120396 0.2794)
			(stroke
				(width 0.1)
				(type default)
			)
			(layer "F.Fab")
		)
		(fp_line
			(start 0.12065 -0.3048)
			(end 0.67945 -0.3048)
			(stroke
				(width 0.1)
				(type default)
			)
			(layer "F.Fab")
		)
		(fp_line
			(start 0.12065 -0.2794)
			(end 0.12065 -0.3048)
			(stroke
				(width 0.1)
				(type default)
			)
			(layer "F.Fab")
		)
		(fp_line
			(start 0.67945 -0.3048)
			(end 0.67945 0.3048)
			(stroke
				(width 0.1)
				(type default)
			)
			(layer "F.Fab")
		)
		(fp_line
			(start 0.67945 0.3048)
			(end 0.120396 0.3048)
			(stroke
				(width 0.1)
				(type default)
			)
			(layer "F.Fab")
		)
		(pad "1" smd circle
			(at -0.40005 0)
			(size 0 0)
			(layers "F.Cu" "F.Mask" "F.Paste")
			(net "P12V_AUX")
		)
		(pad "2" smd circle
			(at 0.40005 0)
			(size 0 0)
			(layers "F.Cu" "F.Mask" "F.Paste")
			(net "P12V_SCM_EN_G")
		)
	)
	(footprint ""
		(layer "F.Cu")
		(at 319.940178 -41.668954)
		(property "Reference" "C2047"
			(at 0 0 0)
			(layer "F.SilkS")
			(hide yes)
			(effects
				(font
					(size 1.27 1.27)
				)
			)
		)
		(property "Value" ""
			(at 0 0 0)
			(layer "F.Fab")
			(effects
				(font
					(size 1.27 1.27)
				)
			)
		)
		(duplicate_pad_numbers_are_jumpers no)
		(fp_line
			(start -0.7874 -0.4064)
			(end 0.7874 -0.4064)
			(stroke
				(width 0.1524)
				(type default)
			)
			(layer "F.SilkS")
		)
		(fp_line
			(start -0.7874 0.4064)
			(end -0.7874 -0.4064)
			(stroke
				(width 0.1524)
				(type default)
			)
			(layer "F.SilkS")
		)
		(fp_line
			(start 0.7874 -0.4064)
			(end 0.7874 0.4064)
			(stroke
				(width 0.1524)
				(type default)
			)
			(layer "F.SilkS")
		)
		(fp_line
			(start 0.7874 0.4064)
			(end -0.7874 0.4064)
			(stroke
				(width 0.1524)
				(type default)
			)
			(layer "F.SilkS")
		)
		(fp_line
			(start -0.67945 -0.305054)
			(end -0.12065 -0.305054)
			(stroke
				(width 0.1)
				(type default)
			)
			(layer "F.Fab")
		)
		(fp_line
			(start -0.67945 0.3048)
			(end -0.67945 -0.305054)
			(stroke
				(width 0.1)
				(type default)
			)
			(layer "F.Fab")
		)
		(fp_line
			(start -0.12065 -0.305054)
			(end -0.12065 -0.2794)
			(stroke
				(width 0.1)
				(type default)
			)
			(layer "F.Fab")
		)
		(fp_line
			(start -0.12065 -0.2794)
			(end 0.12065 -0.2794)
			(stroke
				(width 0.1)
				(type default)
			)
			(layer "F.Fab")
		)
		(fp_line
			(start -0.12065 0.2794)
			(end -0.12065 0.3048)
			(stroke
				(width 0.1)
				(type default)
			)
			(layer "F.Fab")
		)
		(fp_line
			(start -0.12065 0.3048)
			(end -0.67945 0.3048)
			(stroke
				(width 0.1)
				(type default)
			)
			(layer "F.Fab")
		)
		(fp_line
			(start 0.120396 0.2794)
			(end -0.12065 0.2794)
			(stroke
				(width 0.1)
				(type default)
			)
			(layer "F.Fab")
		)
		(fp_line
			(start 0.120396 0.3048)
			(end 0.120396 0.2794)
			(stroke
				(width 0.1)
				(type default)
			)
			(layer "F.Fab")
		)
		(fp_line
			(start 0.12065 -0.3048)
			(end 0.67945 -0.3048)
			(stroke
				(width 0.1)
				(type default)
			)
			(layer "F.Fab")
		)
		(fp_line
			(start 0.12065 -0.2794)
			(end 0.12065 -0.3048)
			(stroke
				(width 0.1)
				(type default)
			)
			(layer "F.Fab")
		)
		(fp_line
			(start 0.67945 -0.3048)
			(end 0.67945 0.3048)
			(stroke
				(width 0.1)
				(type default)
			)
			(layer "F.Fab")
		)
		(fp_line
			(start 0.67945 0.3048)
			(end 0.120396 0.3048)
			(stroke
				(width 0.1)
				(type default)
			)
			(layer "F.Fab")
		)
		(pad "1" smd circle
			(at -0.40005 0)
			(size 0 0)
			(layers "F.Cu" "F.Mask" "F.Paste")
			(net "P3V3_AUX_ADC_TIC")
		)
		(pad "2" smd circle
			(at 0.40005 0)
			(size 0 0)
			(layers "F.Cu" "F.Mask" "F.Paste")
			(net "GND")
		)
	)
)
